(kicad_pcb
	(version 20260206)
	(generator "pcbnew")
	(generator_version "10.0")
	(general
		(thickness 1.6)
		(legacy_teardrops no)
	)
	(paper "A4")
	(title_block
		(title "01162023_DA0F0TEBIF0_F0T_Expander_BD_F_brd_V02_OCP.brd")
		(comment 1 "Grand Teton / footprints 4085-4091 of 9728")
	)
	(layers
		(0 "F.Cu" signal "TOP")
		(4 "In1.Cu" signal "GND")
		(6 "In2.Cu" signal "VCC")
		(8 "In3.Cu" signal "VCC1")
		(10 "In4.Cu" signal "GND1")
		(12 "In5.Cu" signal "IN1")
		(14 "In6.Cu" signal "GND2")
		(16 "In7.Cu" signal "IN2")
		(18 "In8.Cu" signal "GND3")
		(20 "In9.Cu" signal "IN3")
		(22 "In10.Cu" signal "GND4")
		(24 "In11.Cu" signal "IN4")
		(26 "In12.Cu" signal "GND5")
		(28 "In13.Cu" signal "IN5")
		(30 "In14.Cu" signal "GND6")
		(32 "In15.Cu" signal "IN6")
		(34 "In16.Cu" signal "GND7")
		(2 "B.Cu" signal "BOTTOM")
		(9 "F.Adhes" user "F.Adhesive")
		(11 "B.Adhes" user "B.Adhesive")
		(13 "F.Paste" user "Package Geometry/Pastemask Top")
		(15 "B.Paste" user "Package Geometry/Pastemask Bottom")
		(5 "F.SilkS" user "Ref Des/Silkscreen Top")
		(7 "B.SilkS" user "Ref Des/Silkscreen Bottom")
		(1 "F.Mask" user "Board Geometry/Soldermask Top")
		(3 "B.Mask" user "Board Geometry/Soldermask Bottom")
		(17 "Dwgs.User" user "User.Drawings")
		(19 "Cmts.User" user "User.Comments")
		(21 "Eco1.User" user "User.Eco1")
		(23 "Eco2.User" user "User.Eco2")
		(25 "Edge.Cuts" user "Board Geometry/Outline")
		(27 "Margin" user)
		(31 "F.CrtYd" user "Package Geometry/Place Bound Top")
		(29 "B.CrtYd" user "Package Geometry/Place Bound Bottom")
		(35 "F.Fab" user "Ref Des/Assembly Top")
		(33 "B.Fab" user "Ref Des/Assembly Bottom")
	)
	(footprint ""
		(layer "F.Cu")
		(at 219.162376 -22.955504 -90)
		(property "Reference" "C2725"
			(at 0 0 270)
			(layer "F.SilkS")
			(hide yes)
			(effects
				(font
					(size 1.27 1.27)
				)
			)
		)
		(property "Value" ""
			(at 0 0 270)
			(layer "F.Fab")
			(effects
				(font
					(size 1.27 1.27)
				)
			)
		)
		(duplicate_pad_numbers_are_jumpers no)
		(fp_line
			(start -0.7874 0.4064)
			(end -0.7874 -0.4064)
			(stroke
				(width 0.1524)
				(type default)
			)
			(layer "F.SilkS")
		)
		(fp_line
			(start 0.7874 0.4064)
			(end -0.7874 0.4064)
			(stroke
				(width 0.1524)
				(type default)
			)
			(layer "F.SilkS")
		)
		(fp_line
			(start -0.7874 -0.4064)
			(end 0.7874 -0.4064)
			(stroke
				(width 0.1524)
				(type default)
			)
			(layer "F.SilkS")
		)
		(fp_line
			(start 0.7874 -0.4064)
			(end 0.7874 0.4064)
			(stroke
				(width 0.1524)
				(type default)
			)
			(layer "F.SilkS")
		)
		(fp_line
			(start -0.67945 0.3048)
			(end -0.67945 -0.305054)
			(stroke
				(width 0.1)
				(type default)
			)
			(layer "F.Fab")
		)
		(fp_line
			(start -0.12065 0.3048)
			(end -0.67945 0.3048)
			(stroke
				(width 0.1)
				(type default)
			)
			(layer "F.Fab")
		)
		(fp_line
			(start 0.120396 0.3048)
			(end 0.120396 0.2794)
			(stroke
				(width 0.1)
				(type default)
			)
			(layer "F.Fab")
		)
		(fp_line
			(start 0.67945 0.3048)
			(end 0.120396 0.3048)
			(stroke
				(width 0.1)
				(type default)
			)
			(layer "F.Fab")
		)
		(fp_line
			(start -0.12065 0.2794)
			(end -0.12065 0.3048)
			(stroke
				(width 0.1)
				(type default)
			)
			(layer "F.Fab")
		)
		(fp_line
			(start 0.120396 0.2794)
			(end -0.12065 0.2794)
			(stroke
				(width 0.1)
				(type default)
			)
			(layer "F.Fab")
		)
		(fp_line
			(start -0.12065 -0.2794)
			(end 0.12065 -0.2794)
			(stroke
				(width 0.1)
				(type default)
			)
			(layer "F.Fab")
		)
		(fp_line
			(start 0.12065 -0.2794)
			(end 0.12065 -0.3048)
			(stroke
				(width 0.1)
				(type default)
			)
			(layer "F.Fab")
		)
		(fp_line
			(start 0.12065 -0.3048)
			(end 0.67945 -0.3048)
			(stroke
				(width 0.1)
				(type default)
			)
			(layer "F.Fab")
		)
		(fp_line
			(start 0.67945 -0.3048)
			(end 0.67945 0.3048)
			(stroke
				(width 0.1)
				(type default)
			)
			(layer "F.Fab")
		)
		(fp_line
			(start -0.67945 -0.305054)
			(end -0.12065 -0.305054)
			(stroke
				(width 0.1)
				(type default)
			)
			(layer "F.Fab")
		)
		(fp_line
			(start -0.12065 -0.305054)
			(end -0.12065 -0.2794)
			(stroke
				(width 0.1)
				(type default)
			)
			(layer "F.Fab")
		)
		(pad "1" smd circle
			(at -0.40005 0 270)
			(size 0 0)
			(layers "F.Cu" "F.Mask" "F.Paste")
			(net "GND")
		)
		(pad "2" smd circle
			(at 0.40005 0 270)
			(size 0 0)
			(layers "F.Cu" "F.Mask" "F.Paste")
			(net "P3V3_AUX")
		)
	)
	(footprint ""
		(layer "F.Cu")
		(at 19.24685 -38.49116 180)
		(property "Reference" "R5877"
			(at 0 0 180)
			(layer "F.SilkS")
			(hide yes)
			(effects
				(font
					(size 1.27 1.27)
				)
			)
		)
		(property "Value" ""
			(at 0 0 180)
			(layer "F.Fab")
			(effects
				(font
					(size 1.27 1.27)
				)
			)
		)
		(duplicate_pad_numbers_are_jumpers no)
		(fp_line
			(start 0.7874 0.4064)
			(end -0.7874 0.4064)
			(stroke
				(width 0.1524)
				(type default)
			)
			(layer "F.SilkS")
		)
		(fp_line
			(start 0.7874 -0.4064)
			(end 0.7874 0.4064)
			(stroke
				(width 0.1524)
				(type default)
			)
			(layer "F.SilkS")
		)
		(fp_line
			(start -0.7874 0.4064)
			(end -0.7874 -0.4064)
			(stroke
				(width 0.1524)
				(type default)
			)
			(layer "F.SilkS")
		)
		(fp_line
			(start -0.7874 -0.4064)
			(end 0.7874 -0.4064)
			(stroke
				(width 0.1524)
				(type default)
			)
			(layer "F.SilkS")
		)
		(fp_line
			(start 0.67945 0.3048)
			(end 0.120396 0.3048)
			(stroke
				(width 0.1)
				(type default)
			)
			(layer "F.Fab")
		)
		(fp_line
			(start 0.67945 -0.3048)
			(end 0.67945 0.3048)
			(stroke
				(width 0.1)
				(type default)
			)
			(layer "F.Fab")
		)
		(fp_line
			(start 0.12065 -0.2794)
			(end 0.12065 -0.3048)
			(stroke
				(width 0.1)
				(type default)
			)
			(layer "F.Fab")
		)
		(fp_line
			(start 0.12065 -0.3048)
			(end 0.67945 -0.3048)
			(stroke
				(width 0.1)
				(type default)
			)
			(layer "F.Fab")
		)
		(fp_line
			(start 0.120396 0.3048)
			(end 0.120396 0.2794)
			(stroke
				(width 0.1)
				(type default)
			)
			(layer "F.Fab")
		)
		(fp_line
			(start 0.120396 0.2794)
			(end -0.12065 0.2794)
			(stroke
				(width 0.1)
				(type default)
			)
			(layer "F.Fab")
		)
		(fp_line
			(start -0.12065 0.3048)
			(end -0.67945 0.3048)
			(stroke
				(width 0.1)
				(type default)
			)
			(layer "F.Fab")
		)
		(fp_line
			(start -0.12065 0.2794)
			(end -0.12065 0.3048)
			(stroke
				(width 0.1)
				(type default)
			)
			(layer "F.Fab")
		)
		(fp_line
			(start -0.12065 -0.2794)
			(end 0.12065 -0.2794)
			(stroke
				(width 0.1)
				(type default)
			)
			(layer "F.Fab")
		)
		(fp_line
			(start -0.12065 -0.305054)
			(end -0.12065 -0.2794)
			(stroke
				(width 0.1)
				(type default)
			)
			(layer "F.Fab")
		)
		(fp_line
			(start -0.67945 0.3048)
			(end -0.67945 -0.305054)
			(stroke
				(width 0.1)
				(type default)
			)
			(layer "F.Fab")
		)
		(fp_line
			(start -0.67945 -0.305054)
			(end -0.12065 -0.305054)
			(stroke
				(width 0.1)
				(type default)
			)
			(layer "F.Fab")
		)
		(pad "1" smd circle
			(at -0.40005 0 180)
			(size 0 0)
			(layers "F.Cu" "F.Mask" "F.Paste")
			(net "P3V3_SSD1_PG_G1")
		)
		(pad "2" smd circle
			(at 0.40005 0 180)
			(size 0 0)
			(layers "F.Cu" "F.Mask" "F.Paste")
			(net "GND")
		)
	)
	(footprint ""
		(layer "F.Cu")
		(at 451.911466 -71.458074 -90)
		(property "Reference" "PD120"
			(at 4.148074 -2.800604 90)
			(unlocked yes)
			(layer "F.SilkS")
			(effects
				(font
					(size 0.7874 0.5842)
					(thickness 0.1524)
				)
				(justify left)
			)
		)
		(property "Value" ""
			(at 0 0 270)
			(layer "F.Fab")
			(effects
				(font
					(size 1.27 1.27)
				)
			)
		)
		(duplicate_pad_numbers_are_jumpers no)
		(fp_line
			(start -3.656584 1.970024)
			(end 4.240784 1.970024)
			(stroke
				(width 0.1524)
				(type default)
			)
			(layer "F.SilkS")
		)
		(fp_line
			(start 4.240784 1.970024)
			(end 4.240784 -1.970024)
			(stroke
				(width 0.1524)
				(type default)
			)
			(layer "F.SilkS")
		)
		(fp_line
			(start -3.656584 -1.970024)
			(end -3.656584 1.970024)
			(stroke
				(width 0.1524)
				(type default)
			)
			(layer "F.SilkS")
		)
		(fp_line
			(start 4.240784 -1.970024)
			(end -3.656584 -1.970024)
			(stroke
				(width 0.1524)
				(type default)
			)
			(layer "F.SilkS")
		)
		(fp_poly
			(pts
				(xy 3.580384 1.970024) (xy 3.580384 -1.970024) (xy 4.240784 -1.970024) (xy 4.240784 1.970024)
			)
			(stroke
				(width 0)
				(type default)
			)
			(fill yes)
			(layer "F.SilkS")
		)
		(fp_line
			(start -2.3749 1.970024)
			(end 2.3749 1.970024)
			(stroke
				(width 0.1)
				(type default)
			)
			(layer "F.Fab")
		)
		(fp_line
			(start 2.3749 1.970024)
			(end 2.3749 -1.970024)
			(stroke
				(width 0.1)
				(type default)
			)
			(layer "F.Fab")
		)
		(fp_line
			(start -2.3749 -1.970024)
			(end -2.3749 1.970024)
			(stroke
				(width 0.1)
				(type default)
			)
			(layer "F.Fab")
		)
		(fp_line
			(start 2.3749 -1.970024)
			(end -2.3749 -1.970024)
			(stroke
				(width 0.1)
				(type default)
			)
			(layer "F.Fab")
		)
		(fp_text user "+"
			(at -4.9784 -0.23495 270)
			(unlocked yes)
			(layer "F.Fab")
			(effects
				(font
					(size 1.905 1.4224)
					(thickness 0.1524)
				)
				(justify left)
			)
		)
		(fp_text user "-"
			(at 4.1656 -0.23495 270)
			(unlocked yes)
			(layer "F.Fab")
			(effects
				(font
					(size 1.905 1.4224)
					(thickness 0.1524)
				)
				(justify left)
			)
		)
		(pad "A" smd rect
			(at -2.450084 0 270)
			(size 2.159 2.2606)
			(layers "F.Cu" "F.Mask" "F.Paste")
			(net "GND")
		)
		(pad "C" smd rect
			(at 2.450084 0 270)
			(size 2.159 2.2606)
			(layers "F.Cu" "F.Mask" "F.Paste")
			(net "P12V_AUX")
		)
	)
	(footprint ""
		(layer "F.Cu")
		(at 175.203358 -59.571636 90)
		(property "Reference" "PR266"
			(at 0 0 90)
			(layer "F.SilkS")
			(hide yes)
			(effects
				(font
					(size 1.27 1.27)
				)
			)
		)
		(property "Value" ""
			(at 0 0 90)
			(layer "F.Fab")
			(effects
				(font
					(size 1.27 1.27)
				)
			)
		)
		(duplicate_pad_numbers_are_jumpers no)
		(fp_line
			(start 0.7874 -0.4064)
			(end 0.7874 0.4064)
			(stroke
				(width 0.1524)
				(type default)
			)
			(layer "F.SilkS")
		)
		(fp_line
			(start -0.7874 -0.4064)
			(end 0.7874 -0.4064)
			(stroke
				(width 0.1524)
				(type default)
			)
			(layer "F.SilkS")
		)
		(fp_line
			(start 0.7874 0.4064)
			(end -0.7874 0.4064)
			(stroke
				(width 0.1524)
				(type default)
			)
			(layer "F.SilkS")
		)
		(fp_line
			(start -0.7874 0.4064)
			(end -0.7874 -0.4064)
			(stroke
				(width 0.1524)
				(type default)
			)
			(layer "F.SilkS")
		)
		(fp_line
			(start -0.12065 -0.305054)
			(end -0.12065 -0.2794)
			(stroke
				(width 0.1)
				(type default)
			)
			(layer "F.Fab")
		)
		(fp_line
			(start -0.67945 -0.305054)
			(end -0.12065 -0.305054)
			(stroke
				(width 0.1)
				(type default)
			)
			(layer "F.Fab")
		)
		(fp_line
			(start 0.67945 -0.3048)
			(end 0.67945 0.3048)
			(stroke
				(width 0.1)
				(type default)
			)
			(layer "F.Fab")
		)
		(fp_line
			(start 0.12065 -0.3048)
			(end 0.67945 -0.3048)
			(stroke
				(width 0.1)
				(type default)
			)
			(layer "F.Fab")
		)
		(fp_line
			(start 0.12065 -0.2794)
			(end 0.12065 -0.3048)
			(stroke
				(width 0.1)
				(type default)
			)
			(layer "F.Fab")
		)
		(fp_line
			(start -0.12065 -0.2794)
			(end 0.12065 -0.2794)
			(stroke
				(width 0.1)
				(type default)
			)
			(layer "F.Fab")
		)
		(fp_line
			(start 0.120396 0.2794)
			(end -0.12065 0.2794)
			(stroke
				(width 0.1)
				(type default)
			)
			(layer "F.Fab")
		)
		(fp_line
			(start -0.12065 0.2794)
			(end -0.12065 0.3048)
			(stroke
				(width 0.1)
				(type default)
			)
			(layer "F.Fab")
		)
		(fp_line
			(start 0.67945 0.3048)
			(end 0.120396 0.3048)
			(stroke
				(width 0.1)
				(type default)
			)
			(layer "F.Fab")
		)
		(fp_line
			(start 0.120396 0.3048)
			(end 0.120396 0.2794)
			(stroke
				(width 0.1)
				(type default)
			)
			(layer "F.Fab")
		)
		(fp_line
			(start -0.12065 0.3048)
			(end -0.67945 0.3048)
			(stroke
				(width 0.1)
				(type default)
			)
			(layer "F.Fab")
		)
		(fp_line
			(start -0.67945 0.3048)
			(end -0.67945 -0.305054)
			(stroke
				(width 0.1)
				(type default)
			)
			(layer "F.Fab")
		)
		(pad "1" smd circle
			(at -0.40005 0 90)
			(size 0 0)
			(layers "F.Cu" "F.Mask" "F.Paste")
			(net "P3V3_SSD6_OCP")
		)
		(pad "2" smd circle
			(at 0.40005 0 90)
			(size 0 0)
			(layers "F.Cu" "F.Mask" "F.Paste")
			(net "GND")
		)
	)
	(footprint ""
		(layer "F.Cu")
		(at 392.139932 -70.52437 90)
		(property "Reference" "PC886"
			(at 0 0 90)
			(layer "F.SilkS")
			(hide yes)
			(effects
				(font
					(size 1.27 1.27)
				)
			)
		)
		(property "Value" ""
			(at 0 0 90)
			(layer "F.Fab")
			(effects
				(font
					(size 1.27 1.27)
				)
			)
		)
		(duplicate_pad_numbers_are_jumpers no)
		(fp_line
			(start 1.524 -0.762)
			(end 1.524 0.762)
			(stroke
				(width 0.1524)
				(type default)
			)
			(layer "F.SilkS")
		)
		(fp_line
			(start -1.524 -0.762)
			(end 1.524 -0.762)
			(stroke
				(width 0.1524)
				(type default)
			)
			(layer "F.SilkS")
		)
		(fp_line
			(start 1.524 0.762)
			(end -1.524 0.762)
			(stroke
				(width 0.1524)
				(type default)
			)
			(layer "F.SilkS")
		)
		(fp_line
			(start -1.524 0.762)
			(end -1.524 -0.762)
			(stroke
				(width 0.1524)
				(type default)
			)
			(layer "F.SilkS")
		)
		(fp_line
			(start 1.1049 -0.724916)
			(end -1.1049 -0.724916)
			(stroke
				(width 0.1)
				(type default)
			)
			(layer "F.Fab")
		)
		(fp_line
			(start -1.1049 -0.724916)
			(end -1.1049 0.724916)
			(stroke
				(width 0.1)
				(type default)
			)
			(layer "F.Fab")
		)
		(fp_line
			(start 1.1049 0.724916)
			(end 1.1049 -0.724916)
			(stroke
				(width 0.1)
				(type default)
			)
			(layer "F.Fab")
		)
		(fp_line
			(start -1.1049 0.724916)
			(end 1.1049 0.724916)
			(stroke
				(width 0.1)
				(type default)
			)
			(layer "F.Fab")
		)
		(pad "1" smd rect
			(at -0.889 0 270)
			(size 1.016 1.27)
			(layers "F.Cu" "F.Mask" "F.Paste")
			(net "P12V_SSD13_R")
		)
		(pad "2" smd rect
			(at 0.889 0 270)
			(size 1.016 1.27)
			(layers "F.Cu" "F.Mask" "F.Paste")
			(net "GND")
		)
	)
	(footprint ""
		(layer "F.Cu")
		(at 344.511884 -108.737654 180)
		(property "Reference" "C844"
			(at 0 0 180)
			(layer "F.SilkS")
			(hide yes)
			(effects
				(font
					(size 1.27 1.27)
				)
			)
		)
		(property "Value" ""
			(at 0 0 180)
			(layer "F.Fab")
			(effects
				(font
					(size 1.27 1.27)
				)
			)
		)
		(duplicate_pad_numbers_are_jumpers no)
		(fp_line
			(start 0.7874 0.4064)
			(end -0.7874 0.4064)
			(stroke
				(width 0.1524)
				(type default)
			)
			(layer "F.SilkS")
		)
		(fp_line
			(start 0.7874 -0.4064)
			(end 0.7874 0.4064)
			(stroke
				(width 0.1524)
				(type default)
			)
			(layer "F.SilkS")
		)
		(fp_line
			(start -0.7874 0.4064)
			(end -0.7874 -0.4064)
			(stroke
				(width 0.1524)
				(type default)
			)
			(layer "F.SilkS")
		)
		(fp_line
			(start -0.7874 -0.4064)
			(end 0.7874 -0.4064)
			(stroke
				(width 0.1524)
				(type default)
			)
			(layer "F.SilkS")
		)
		(fp_line
			(start 0.67945 0.3048)
			(end 0.120396 0.3048)
			(stroke
				(width 0.1)
				(type default)
			)
			(layer "F.Fab")
		)
		(fp_line
			(start 0.67945 -0.3048)
			(end 0.67945 0.3048)
			(stroke
				(width 0.1)
				(type default)
			)
			(layer "F.Fab")
		)
		(fp_line
			(start 0.12065 -0.2794)
			(end 0.12065 -0.3048)
			(stroke
				(width 0.1)
				(type default)
			)
			(layer "F.Fab")
		)
		(fp_line
			(start 0.12065 -0.3048)
			(end 0.67945 -0.3048)
			(stroke
				(width 0.1)
				(type default)
			)
			(layer "F.Fab")
		)
		(fp_line
			(start 0.120396 0.3048)
			(end 0.120396 0.2794)
			(stroke
				(width 0.1)
				(type default)
			)
			(layer "F.Fab")
		)
		(fp_line
			(start 0.120396 0.2794)
			(end -0.12065 0.2794)
			(stroke
				(width 0.1)
				(type default)
			)
			(layer "F.Fab")
		)
		(fp_line
			(start -0.12065 0.3048)
			(end -0.67945 0.3048)
			(stroke
				(width 0.1)
				(type default)
			)
			(layer "F.Fab")
		)
		(fp_line
			(start -0.12065 0.2794)
			(end -0.12065 0.3048)
			(stroke
				(width 0.1)
				(type default)
			)
			(layer "F.Fab")
		)
		(fp_line
			(start -0.12065 -0.2794)
			(end 0.12065 -0.2794)
			(stroke
				(width 0.1)
				(type default)
			)
			(layer "F.Fab")
		)
		(fp_line
			(start -0.12065 -0.305054)
			(end -0.12065 -0.2794)
			(stroke
				(width 0.1)
				(type default)
			)
			(layer "F.Fab")
		)
		(fp_line
			(start -0.67945 0.3048)
			(end -0.67945 -0.305054)
			(stroke
				(width 0.1)
				(type default)
			)
			(layer "F.Fab")
		)
		(fp_line
			(start -0.67945 -0.305054)
			(end -0.12065 -0.305054)
			(stroke
				(width 0.1)
				(type default)
			)
			(layer "F.Fab")
		)
		(pad "1" smd circle
			(at -0.40005 0 180)
			(size 0 0)
			(layers "F.Cu" "F.Mask" "F.Paste")
			(net "GND")
		)
		(pad "2" smd circle
			(at 0.40005 0 180)
			(size 0 0)
			(layers "F.Cu" "F.Mask" "F.Paste")
			(net "P12V_NIC5_CO_EN")
		)
	)
	(footprint ""
		(layer "F.Cu")
		(at 258.806188 -204.29601 -90)
		(property "Reference" "R2537"
			(at 0 0 270)
			(layer "F.SilkS")
			(hide yes)
			(effects
				(font
					(size 1.27 1.27)
				)
			)
		)
		(property "Value" ""
			(at 0 0 270)
			(layer "F.Fab")
			(effects
				(font
					(size 1.27 1.27)
				)
			)
		)
		(duplicate_pad_numbers_are_jumpers no)
		(fp_line
			(start -0.7874 0.4064)
			(end -0.7874 -0.4064)
			(stroke
				(width 0.1524)
				(type default)
			)
			(layer "F.SilkS")
		)
		(fp_line
			(start 0.7874 0.4064)
			(end -0.7874 0.4064)
			(stroke
				(width 0.1524)
				(type default)
			)
			(layer "F.SilkS")
		)
		(fp_line
			(start -0.7874 -0.4064)
			(end 0.7874 -0.4064)
			(stroke
				(width 0.1524)
				(type default)
			)
			(layer "F.SilkS")
		)
		(fp_line
			(start 0.7874 -0.4064)
			(end 0.7874 0.4064)
			(stroke
				(width 0.1524)
				(type default)
			)
			(layer "F.SilkS")
		)
		(fp_line
			(start -0.67945 0.3048)
			(end -0.67945 -0.305054)
			(stroke
				(width 0.1)
				(type default)
			)
			(layer "F.Fab")
		)
		(fp_line
			(start -0.12065 0.3048)
			(end -0.67945 0.3048)
			(stroke
				(width 0.1)
				(type default)
			)
			(layer "F.Fab")
		)
		(fp_line
			(start 0.120396 0.3048)
			(end 0.120396 0.2794)
			(stroke
				(width 0.1)
				(type default)
			)
			(layer "F.Fab")
		)
		(fp_line
			(start 0.67945 0.3048)
			(end 0.120396 0.3048)
			(stroke
				(width 0.1)
				(type default)
			)
			(layer "F.Fab")
		)
		(fp_line
			(start -0.12065 0.2794)
			(end -0.12065 0.3048)
			(stroke
				(width 0.1)
				(type default)
			)
			(layer "F.Fab")
		)
		(fp_line
			(start 0.120396 0.2794)
			(end -0.12065 0.2794)
			(stroke
				(width 0.1)
				(type default)
			)
			(layer "F.Fab")
		)
		(fp_line
			(start -0.12065 -0.2794)
			(end 0.12065 -0.2794)
			(stroke
				(width 0.1)
				(type default)
			)
			(layer "F.Fab")
		)
		(fp_line
			(start 0.12065 -0.2794)
			(end 0.12065 -0.3048)
			(stroke
				(width 0.1)
				(type default)
			)
			(layer "F.Fab")
		)
		(fp_line
			(start 0.12065 -0.3048)
			(end 0.67945 -0.3048)
			(stroke
				(width 0.1)
				(type default)
			)
			(layer "F.Fab")
		)
		(fp_line
			(start 0.67945 -0.3048)
			(end 0.67945 0.3048)
			(stroke
				(width 0.1)
				(type default)
			)
			(layer "F.Fab")
		)
		(fp_line
			(start -0.67945 -0.305054)
			(end -0.12065 -0.305054)
			(stroke
				(width 0.1)
				(type default)
			)
			(layer "F.Fab")
		)
		(fp_line
			(start -0.12065 -0.305054)
			(end -0.12065 -0.2794)
			(stroke
				(width 0.1)
				(type default)
			)
			(layer "F.Fab")
		)
		(pad "1" smd circle
			(at -0.40005 0 270)
			(size 0 0)
			(layers "F.Cu" "F.Mask" "F.Paste")
			(net "JTAG_FPGA_TDI")
		)
		(pad "2" smd circle
			(at 0.40005 0 270)
			(size 0 0)
			(layers "F.Cu" "F.Mask" "F.Paste")
			(net "JTAG_CONN_TDI")
		)
	)
)
